FILE_TYPE = MACRO_DRAWING;
SET COLOR_WIRE YELLOW;
SET COLOR_PROP ORANGE;
SET COLOR_DOT WHITE;
SET COLOR_ARC YELLOW;
SET COLOR_BODY GREEN;
SET COLOR_NOTE PURPLE;
SET PROP_DISPLAY VALUE;
SET PAGE_NUMBER P75;
FORCEADD OFFPAGE..2
(-7225 4250);
FORCEPROP 2 LAST $XR2 141 
J 0
(-6856 4250);
DISPLAY 0.638298 (-6856 4250);
PAINT MONO (-6856 4250);
FORCEPROP 2 LAST $XR1 75 
J 0
(-6946 4250);
DISPLAY 0.638298 (-6946 4250);
PAINT MONO (-6946 4250);
FORCEPROP 2 LAST $XR0 27 
J 0
(-7036 4250);
DISPLAY 0.638298 (-7036 4250);
PAINT MONO (-7036 4250);
FORCEPROP 2 LAST PATH I1
J 0
(-6925 4300);
DISPLAY 1.021277 (-6925 4300);
DISPLAY INVISIBLE (-6925 4300);
FORCEPROP 1 LAST COMMENT_BODY TRUE
J 0
(-7270 4155);
DISPLAY 0.872340 (-7270 4155);
PAINT GREEN (-7270 4155);
DISPLAY INVISIBLE (-7270 4155);
FORCEPROP 1 LAST OFFPAGE TRUE
J 0
(-6900 4125);
DISPLAY 0.872340 (-6900 4125);
PAINT GREEN (-6900 4125);
DISPLAY INVISIBLE (-6900 4125);
FORCEPROP 2 LAST CDS_LIB standard
J 0
(-7225 4250);
DISPLAY INVISIBLE (-7225 4250);
FORCEADD Q_RES..1
(-8650 3600);
FORCEPROP 1 LAST LOCATION R751
J 0
(-8875 3600);
DISPLAY 0.489362 (-8875 3600);
PAINT SKYBLUE (-8875 3600);
FORCEPROP 2 LAST $SEC 1
J 0
(-8700 3800);
DISPLAY 0.680851 (-8700 3800);
PAINT MONO (-8700 3800);
DISPLAY INVISIBLE (-8700 3800);
FORCEPROP 2 LAST CDS_SEC 1
J 0
(-8700 3800);
DISPLAY 1.021277 (-8700 3800);
DISPLAY INVISIBLE (-8700 3800);
FORCEPROP 1 LASTPIN (-8750 3600) $PN 1
J 0
(-8738 3612);
DISPLAY 0.489362 (-8738 3612);
FORCEPROP 1 LASTPIN (-8550 3600) $PN 2
J 0
(-8588 3612);
DISPLAY 0.489362 (-8588 3612);
FORCEPROP 1 LAST MATERIAL CHIP
J 0
(-8325 3600);
DISPLAY 0.489362 (-8325 3600);
PAINT SKYBLUE (-8325 3600);
FORCEPROP 1 LAST TOLERANCE 5%
J 0
(-8425 3600);
DISPLAY 0.489362 (-8425 3600);
PAINT SKYBLUE (-8425 3600);
FORCEPROP 1 LAST VALUE 10K
J 2
(-8450 3600);
DISPLAY 0.489362 (-8450 3600);
PAINT SKYBLUE (-8450 3600);
FORCEPROP 2 LAST CDS_LIB pure_quanta
J 0
(-8650 3600);
PAINT MONO (-8650 3600);
DISPLAY INVISIBLE (-8650 3600);
FORCEPROP 1 LAST PATH I12
J 0
(-8700 3750);
DISPLAY 0.978723 (-8700 3750);
PAINT WHITE (-8700 3750);
DISPLAY INVISIBLE (-8700 3750);
FORCEPROP 1 LAST WATTAGE 1/16W
J 2
(-8475 3675);
DISPLAY 0.510638 (-8475 3675);
PAINT SKYBLUE (-8475 3675);
DISPLAY INVISIBLE (-8475 3675);
FORCEPROP 1 LAST PART_NUMBER TMP_QCS31002JB28
J 0
(-8750 3650);
DISPLAY 0.510638 (-8750 3650);
PAINT SKYBLUE (-8750 3650);
DISPLAY INVISIBLE (-8750 3650);
FORCEPROP 1 LAST PACK_TYPE 0402LF
J 0
(-8750 3675);
DISPLAY 0.510638 (-8750 3675);
PAINT SKYBLUE (-8750 3675);
DISPLAY INVISIBLE (-8750 3675);
FORCEADD UNIVERSAL_GND..1
(-8950 3225);
FORCEPROP 3 LASTPIN (-8950 3275) SIG_NAME GND\g
J 0
(-8940 3285);
DISPLAY 0.659574 (-8940 3285);
PAINT MONO (-8940 3285);
DISPLAY INVISIBLE (-8940 3285);
FORCEPROP 2 LAST CDS_LIB pure_quanta_power
J 0
(-8950 3225);
DISPLAY INVISIBLE (-8950 3225);
FORCEPROP 1 LAST PATH I15
J 0
(-8875 3225);
DISPLAY 0.872340 (-8875 3225);
PAINT AQUA (-8875 3225);
DISPLAY INVISIBLE (-8875 3225);
FORCEPROP 1 LAST HDL_POWER GND
J 1
(-8925 3150);
DISPLAY 0.872340 (-8925 3150);
PAINT GREEN (-8925 3150);
DISPLAY INVISIBLE (-8925 3150);
FORCEADD OFFPAGE..2
(-7225 5450);
FORCEPROP 2 LAST $XR2 141 
J 0
(-6856 5450);
DISPLAY 0.638298 (-6856 5450);
PAINT MONO (-6856 5450);
FORCEPROP 2 LAST $XR1 75 
J 0
(-6946 5450);
DISPLAY 0.638298 (-6946 5450);
PAINT MONO (-6946 5450);
FORCEPROP 2 LAST $XR0 27 
J 0
(-7036 5450);
DISPLAY 0.638298 (-7036 5450);
PAINT MONO (-7036 5450);
FORCEPROP 2 LAST CDS_LIB standard
J 0
(-7225 5450);
DISPLAY INVISIBLE (-7225 5450);
FORCEPROP 1 LAST OFFPAGE TRUE
J 0
(-6900 5325);
DISPLAY 0.872340 (-6900 5325);
PAINT GREEN (-6900 5325);
DISPLAY INVISIBLE (-6900 5325);
FORCEPROP 1 LAST COMMENT_BODY TRUE
J 0
(-7270 5355);
DISPLAY 0.872340 (-7270 5355);
PAINT GREEN (-7270 5355);
DISPLAY INVISIBLE (-7270 5355);
FORCEPROP 2 LAST PATH I27
J 0
(-6850 5500);
DISPLAY 1.021277 (-6850 5500);
DISPLAY INVISIBLE (-6850 5500);
FORCEADD OFFPAGE..2
(-7225 5175);
FORCEPROP 2 LAST $XR1 28 
J 0
(-6946 5175);
DISPLAY 0.638298 (-6946 5175);
PAINT MONO (-6946 5175);
FORCEPROP 2 LAST $XR0 75 
J 0
(-7036 5175);
DISPLAY 0.638298 (-7036 5175);
PAINT MONO (-7036 5175);
FORCEPROP 2 LAST CDS_LIB standard
J 0
(-7225 5175);
DISPLAY INVISIBLE (-7225 5175);
FORCEPROP 1 LAST OFFPAGE TRUE
J 0
(-6900 5050);
DISPLAY 0.872340 (-6900 5050);
PAINT GREEN (-6900 5050);
DISPLAY INVISIBLE (-6900 5050);
FORCEPROP 1 LAST COMMENT_BODY TRUE
J 0
(-7270 5080);
DISPLAY 0.872340 (-7270 5080);
PAINT GREEN (-7270 5080);
DISPLAY INVISIBLE (-7270 5080);
FORCEPROP 2 LAST PATH I28
J 0
(-6925 5225);
DISPLAY 1.021277 (-6925 5225);
DISPLAY INVISIBLE (-6925 5225);
FORCEADD OFFPAGE..2
(-7225 3975);
FORCEPROP 2 LAST $XR1 28 
J 0
(-6946 3975);
DISPLAY 0.638298 (-6946 3975);
PAINT MONO (-6946 3975);
FORCEPROP 2 LAST $XR0 75 
J 0
(-7036 3975);
DISPLAY 0.638298 (-7036 3975);
PAINT MONO (-7036 3975);
FORCEPROP 2 LAST CDS_LIB standard
J 0
(-7225 3975);
DISPLAY INVISIBLE (-7225 3975);
FORCEPROP 1 LAST OFFPAGE TRUE
J 0
(-6900 3850);
DISPLAY 0.872340 (-6900 3850);
PAINT GREEN (-6900 3850);
DISPLAY INVISIBLE (-6900 3850);
FORCEPROP 1 LAST COMMENT_BODY TRUE
J 0
(-7270 3880);
DISPLAY 0.872340 (-7270 3880);
PAINT GREEN (-7270 3880);
DISPLAY INVISIBLE (-7270 3880);
FORCEPROP 2 LAST PATH I3
J 0
(-6925 4025);
DISPLAY 1.021277 (-6925 4025);
DISPLAY INVISIBLE (-6925 4025);
FORCEADD OFFPAGE..2
(-7225 4550);
FORCEPROP 2 LAST $XR1 29 
J 0
(-6946 4550);
DISPLAY 0.638298 (-6946 4550);
PAINT MONO (-6946 4550);
FORCEPROP 2 LAST $XR0 75 
J 0
(-7036 4550);
DISPLAY 0.638298 (-7036 4550);
PAINT MONO (-7036 4550);
FORCEPROP 2 LAST CDS_LIB standard
J 0
(-7225 4550);
DISPLAY INVISIBLE (-7225 4550);
FORCEPROP 1 LAST OFFPAGE TRUE
J 0
(-6900 4425);
DISPLAY 0.872340 (-6900 4425);
PAINT GREEN (-6900 4425);
DISPLAY INVISIBLE (-6900 4425);
FORCEPROP 1 LAST COMMENT_BODY TRUE
J 0
(-7270 4455);
DISPLAY 0.872340 (-7270 4455);
PAINT GREEN (-7270 4455);
DISPLAY INVISIBLE (-7270 4455);
FORCEPROP 2 LAST PATH I32
J 0
(-6925 4600);
DISPLAY 1.021277 (-6925 4600);
DISPLAY INVISIBLE (-6925 4600);
FORCEADD OFFPAGE..2
(-7225 4800);
FORCEPROP 2 LAST $XR2 55 
J 0
(-6856 4800);
DISPLAY 0.638298 (-6856 4800);
PAINT MONO (-6856 4800);
FORCEPROP 2 LAST $XR1 75 
J 0
(-6946 4800);
DISPLAY 0.638298 (-6946 4800);
PAINT MONO (-6946 4800);
FORCEPROP 2 LAST $XR0 28 
J 0
(-7036 4800);
DISPLAY 0.638298 (-7036 4800);
PAINT MONO (-7036 4800);
FORCEPROP 2 LAST CDS_LIB standard
J 0
(-7225 4800);
DISPLAY INVISIBLE (-7225 4800);
FORCEPROP 1 LAST OFFPAGE TRUE
J 0
(-6900 4675);
DISPLAY 0.872340 (-6900 4675);
PAINT GREEN (-6900 4675);
DISPLAY INVISIBLE (-6900 4675);
FORCEPROP 1 LAST COMMENT_BODY TRUE
J 0
(-7270 4705);
DISPLAY 0.872340 (-7270 4705);
PAINT GREEN (-7270 4705);
DISPLAY INVISIBLE (-7270 4705);
FORCEPROP 2 LAST PATH I33
J 0
(-6850 4850);
DISPLAY 1.021277 (-6850 4850);
DISPLAY INVISIBLE (-6850 4850);
FORCEADD OFFPAGE..2
(-7225 4925);
FORCEPROP 2 LAST $XR3 117 
J 0
(-6766 4925);
DISPLAY 0.638298 (-6766 4925);
PAINT MONO (-6766 4925);
FORCEPROP 2 LAST $XR2 80 
J 0
(-6856 4925);
DISPLAY 0.638298 (-6856 4925);
PAINT MONO (-6856 4925);
FORCEPROP 2 LAST $XR1 75 
J 0
(-6946 4925);
DISPLAY 0.638298 (-6946 4925);
PAINT MONO (-6946 4925);
FORCEPROP 2 LAST $XR0 29 
J 0
(-7036 4925);
DISPLAY 0.638298 (-7036 4925);
PAINT MONO (-7036 4925);
FORCEPROP 2 LAST CDS_LIB standard
J 0
(-7225 4925);
DISPLAY INVISIBLE (-7225 4925);
FORCEPROP 1 LAST OFFPAGE TRUE
J 0
(-6900 4800);
DISPLAY 0.872340 (-6900 4800);
PAINT GREEN (-6900 4800);
DISPLAY INVISIBLE (-6900 4800);
FORCEPROP 1 LAST COMMENT_BODY TRUE
J 0
(-7270 4830);
DISPLAY 0.872340 (-7270 4830);
PAINT GREEN (-7270 4830);
DISPLAY INVISIBLE (-7270 4830);
FORCEPROP 2 LAST PATH I35
J 0
(-6850 4975);
DISPLAY 1.021277 (-6850 4975);
DISPLAY INVISIBLE (-6850 4975);
FORCEADD UNIVERSAL_POWER..1
(-8950 5950);
FORCEPROP 3 LASTPIN (-8950 5900) SIG_NAME PVDD18_S5_P0\g
J 0
(-8940 5910);
DISPLAY 0.659574 (-8940 5910);
PAINT MONO (-8940 5910);
DISPLAY INVISIBLE (-8940 5910);
FORCEPROP 1 LAST HDL_POWER PVDD18_S5_P0
J 1
(-8950 6000);
DISPLAY 0.489362 (-8950 6000);
PAINT GREEN (-8950 6000);
FORCEPROP 2 LAST CDS_LIB pure_quanta_power
J 0
(-8950 5950);
DISPLAY INVISIBLE (-8950 5950);
FORCEPROP 1 LAST PATH I39
J 0
(-8900 5975);
DISPLAY 0.872340 (-8900 5975);
PAINT AQUA (-8900 5975);
DISPLAY INVISIBLE (-8900 5975);
FORCEADD OFFPAGE..2
(-7225 3600);
FORCEPROP 2 LAST $XR2 55 
J 0
(-6856 3600);
DISPLAY 0.638298 (-6856 3600);
PAINT MONO (-6856 3600);
FORCEPROP 2 LAST $XR1 75 
J 0
(-6946 3600);
DISPLAY 0.638298 (-6946 3600);
PAINT MONO (-6946 3600);
FORCEPROP 2 LAST $XR0 28 
J 0
(-7036 3600);
DISPLAY 0.638298 (-7036 3600);
PAINT MONO (-7036 3600);
FORCEPROP 2 LAST CDS_LIB standard
J 0
(-7225 3600);
DISPLAY INVISIBLE (-7225 3600);
FORCEPROP 1 LAST OFFPAGE TRUE
J 0
(-6900 3475);
DISPLAY 0.872340 (-6900 3475);
PAINT GREEN (-6900 3475);
DISPLAY INVISIBLE (-6900 3475);
FORCEPROP 1 LAST COMMENT_BODY TRUE
J 0
(-7270 3505);
DISPLAY 0.872340 (-7270 3505);
PAINT GREEN (-7270 3505);
DISPLAY INVISIBLE (-7270 3505);
FORCEPROP 2 LAST PATH I4
J 0
(-6925 3650);
DISPLAY 1.021277 (-6925 3650);
DISPLAY INVISIBLE (-6925 3650);
FORCEADD Q_RES..1
(-8650 5450);
FORCEPROP 1 LAST LOCATION R729
J 0
(-8875 5450);
DISPLAY 0.489362 (-8875 5450);
PAINT SKYBLUE (-8875 5450);
FORCEPROP 2 LAST $SEC 1
J 0
(-8700 5650);
DISPLAY 0.680851 (-8700 5650);
PAINT MONO (-8700 5650);
DISPLAY INVISIBLE (-8700 5650);
FORCEPROP 2 LAST CDS_SEC 1
J 0
(-8700 5650);
DISPLAY 1.021277 (-8700 5650);
DISPLAY INVISIBLE (-8700 5650);
FORCEPROP 1 LASTPIN (-8750 5450) $PN 1
J 0
(-8738 5462);
DISPLAY 0.489362 (-8738 5462);
FORCEPROP 1 LASTPIN (-8550 5450) $PN 2
J 0
(-8588 5462);
DISPLAY 0.489362 (-8588 5462);
FORCEPROP 1 LAST MATERIAL EMPTY
J 0
(-8325 5450);
DISPLAY 0.489362 (-8325 5450);
PAINT RED (-8325 5450);
FORCEPROP 1 LAST TOLERANCE 5%
J 0
(-8425 5450);
DISPLAY 0.489362 (-8425 5450);
PAINT SKYBLUE (-8425 5450);
FORCEPROP 1 LAST VALUE 10K
J 2
(-8450 5450);
DISPLAY 0.489362 (-8450 5450);
PAINT SKYBLUE (-8450 5450);
FORCEPROP 2 LAST CDS_LIB pure_quanta
J 0
(-8650 5450);
PAINT MONO (-8650 5450);
DISPLAY INVISIBLE (-8650 5450);
FORCEPROP 1 LAST PATH I41
J 0
(-8700 5600);
DISPLAY 0.978723 (-8700 5600);
PAINT WHITE (-8700 5600);
DISPLAY INVISIBLE (-8700 5600);
FORCEPROP 1 LAST WATTAGE 1/16W
J 2
(-8475 5525);
DISPLAY 0.510638 (-8475 5525);
PAINT SKYBLUE (-8475 5525);
DISPLAY INVISIBLE (-8475 5525);
FORCEPROP 1 LAST PART_NUMBER TMP_QCS31002JB28
J 0
(-8750 5500);
DISPLAY 0.510638 (-8750 5500);
PAINT SKYBLUE (-8750 5500);
DISPLAY INVISIBLE (-8750 5500);
FORCEPROP 1 LAST PACK_TYPE 0402LF
J 0
(-8750 5525);
DISPLAY 0.510638 (-8750 5525);
PAINT SKYBLUE (-8750 5525);
DISPLAY INVISIBLE (-8750 5525);
FORCEADD Q_RES..1
(-8625 5175);
FORCEPROP 1 LAST LOCATION R737
J 0
(-8875 5175);
DISPLAY 0.489362 (-8875 5175);
PAINT SKYBLUE (-8875 5175);
FORCEPROP 2 LAST $SEC 1
J 0
(-8675 5375);
DISPLAY 0.680851 (-8675 5375);
PAINT MONO (-8675 5375);
DISPLAY INVISIBLE (-8675 5375);
FORCEPROP 2 LAST CDS_SEC 1
J 0
(-8675 5375);
DISPLAY 1.021277 (-8675 5375);
DISPLAY INVISIBLE (-8675 5375);
FORCEPROP 1 LASTPIN (-8725 5175) $PN 1
J 0
(-8713 5187);
DISPLAY 0.489362 (-8713 5187);
FORCEPROP 1 LASTPIN (-8525 5175) $PN 2
J 0
(-8563 5187);
DISPLAY 0.489362 (-8563 5187);
FORCEPROP 1 LAST MATERIAL CHIP
J 0
(-8300 5175);
DISPLAY 0.489362 (-8300 5175);
PAINT SKYBLUE (-8300 5175);
FORCEPROP 1 LAST TOLERANCE 5%
J 0
(-8400 5175);
DISPLAY 0.489362 (-8400 5175);
PAINT SKYBLUE (-8400 5175);
FORCEPROP 1 LAST VALUE 10K
J 2
(-8425 5175);
DISPLAY 0.489362 (-8425 5175);
PAINT SKYBLUE (-8425 5175);
FORCEPROP 2 LAST CDS_LIB pure_quanta
J 0
(-8625 5175);
PAINT MONO (-8625 5175);
DISPLAY INVISIBLE (-8625 5175);
FORCEPROP 1 LAST PATH I43
J 0
(-8675 5325);
DISPLAY 0.978723 (-8675 5325);
PAINT WHITE (-8675 5325);
DISPLAY INVISIBLE (-8675 5325);
FORCEPROP 1 LAST WATTAGE 1/16W
J 2
(-8425 5250);
DISPLAY 0.510638 (-8425 5250);
PAINT SKYBLUE (-8425 5250);
DISPLAY INVISIBLE (-8425 5250);
FORCEPROP 1 LAST PART_NUMBER TMP_QCS31002JB28
J 0
(-8725 5225);
DISPLAY 0.510638 (-8725 5225);
PAINT SKYBLUE (-8725 5225);
DISPLAY INVISIBLE (-8725 5225);
FORCEPROP 1 LAST PACK_TYPE 0402LF
J 0
(-8725 5250);
DISPLAY 0.510638 (-8725 5250);
PAINT SKYBLUE (-8725 5250);
DISPLAY INVISIBLE (-8725 5250);
FORCEADD Q_RES..1
(-8625 4800);
FORCEPROP 1 LAST LOCATION R740
J 0
(-8875 4800);
DISPLAY 0.489362 (-8875 4800);
PAINT SKYBLUE (-8875 4800);
FORCEPROP 2 LAST $SEC 1
J 0
(-8675 5000);
DISPLAY 0.680851 (-8675 5000);
PAINT MONO (-8675 5000);
DISPLAY INVISIBLE (-8675 5000);
FORCEPROP 2 LAST CDS_SEC 1
J 0
(-8675 5000);
DISPLAY 1.021277 (-8675 5000);
DISPLAY INVISIBLE (-8675 5000);
FORCEPROP 1 LASTPIN (-8725 4800) $PN 1
J 0
(-8713 4812);
DISPLAY 0.489362 (-8713 4812);
FORCEPROP 1 LASTPIN (-8525 4800) $PN 2
J 0
(-8563 4812);
DISPLAY 0.489362 (-8563 4812);
FORCEPROP 1 LAST MATERIAL EMPTY
J 0
(-8300 4800);
DISPLAY 0.489362 (-8300 4800);
PAINT RED (-8300 4800);
FORCEPROP 1 LAST TOLERANCE 5%
J 0
(-8400 4800);
DISPLAY 0.489362 (-8400 4800);
PAINT SKYBLUE (-8400 4800);
FORCEPROP 1 LAST VALUE 10K
J 2
(-8425 4800);
DISPLAY 0.489362 (-8425 4800);
PAINT SKYBLUE (-8425 4800);
FORCEPROP 2 LAST CDS_LIB pure_quanta
J 0
(-8625 4800);
PAINT MONO (-8625 4800);
DISPLAY INVISIBLE (-8625 4800);
FORCEPROP 1 LAST PATH I44
J 0
(-8675 4950);
DISPLAY 0.978723 (-8675 4950);
PAINT WHITE (-8675 4950);
DISPLAY INVISIBLE (-8675 4950);
FORCEPROP 1 LAST WATTAGE 1/16W
J 2
(-8450 4875);
DISPLAY 0.510638 (-8450 4875);
PAINT SKYBLUE (-8450 4875);
DISPLAY INVISIBLE (-8450 4875);
FORCEPROP 1 LAST PART_NUMBER TMP_QCS31002JB28
J 0
(-8725 4850);
DISPLAY 0.510638 (-8725 4850);
PAINT SKYBLUE (-8725 4850);
DISPLAY INVISIBLE (-8725 4850);
FORCEPROP 1 LAST PACK_TYPE 0402LF
J 0
(-8725 4875);
DISPLAY 0.510638 (-8725 4875);
PAINT SKYBLUE (-8725 4875);
DISPLAY INVISIBLE (-8725 4875);
FORCEADD Q_RES..1
(-8625 4925);
FORCEPROP 1 LAST LOCATION R739
J 0
(-8875 4925);
DISPLAY 0.489362 (-8875 4925);
PAINT SKYBLUE (-8875 4925);
FORCEPROP 2 LAST $SEC 1
J 0
(-8675 5125);
DISPLAY 0.680851 (-8675 5125);
PAINT MONO (-8675 5125);
DISPLAY INVISIBLE (-8675 5125);
FORCEPROP 2 LAST CDS_SEC 1
J 0
(-8675 5125);
DISPLAY 1.021277 (-8675 5125);
DISPLAY INVISIBLE (-8675 5125);
FORCEPROP 1 LASTPIN (-8725 4925) $PN 1
J 0
(-8713 4937);
DISPLAY 0.489362 (-8713 4937);
FORCEPROP 1 LASTPIN (-8525 4925) $PN 2
J 0
(-8563 4937);
DISPLAY 0.489362 (-8563 4937);
FORCEPROP 1 LAST MATERIAL EMPTY
J 0
(-8300 4925);
DISPLAY 0.489362 (-8300 4925);
PAINT RED (-8300 4925);
FORCEPROP 1 LAST TOLERANCE 5%
J 0
(-8400 4925);
DISPLAY 0.489362 (-8400 4925);
PAINT SKYBLUE (-8400 4925);
FORCEPROP 1 LAST VALUE 10K
J 2
(-8425 4925);
DISPLAY 0.489362 (-8425 4925);
PAINT SKYBLUE (-8425 4925);
FORCEPROP 2 LAST CDS_LIB pure_quanta
J 0
(-8625 4925);
PAINT MONO (-8625 4925);
DISPLAY INVISIBLE (-8625 4925);
FORCEPROP 1 LAST PATH I45
J 0
(-8675 5075);
DISPLAY 0.978723 (-8675 5075);
PAINT WHITE (-8675 5075);
DISPLAY INVISIBLE (-8675 5075);
FORCEPROP 1 LAST WATTAGE 1/16W
J 2
(-8450 5000);
DISPLAY 0.510638 (-8450 5000);
PAINT SKYBLUE (-8450 5000);
DISPLAY INVISIBLE (-8450 5000);
FORCEPROP 1 LAST PART_NUMBER TMP_QCS31002JB28
J 0
(-8725 4975);
DISPLAY 0.510638 (-8725 4975);
PAINT SKYBLUE (-8725 4975);
DISPLAY INVISIBLE (-8725 4975);
FORCEPROP 1 LAST PACK_TYPE 0402LF
J 0
(-8725 5000);
DISPLAY 0.510638 (-8725 5000);
PAINT SKYBLUE (-8725 5000);
DISPLAY INVISIBLE (-8725 5000);
FORCEADD Q_RES..1
(-8625 4550);
FORCEPROP 1 LAST LOCATION R742
J 0
(-8875 4550);
DISPLAY 0.489362 (-8875 4550);
PAINT SKYBLUE (-8875 4550);
FORCEPROP 2 LAST $SEC 1
J 0
(-8675 4750);
DISPLAY 0.680851 (-8675 4750);
PAINT MONO (-8675 4750);
DISPLAY INVISIBLE (-8675 4750);
FORCEPROP 2 LAST CDS_SEC 1
J 0
(-8675 4750);
DISPLAY 1.021277 (-8675 4750);
DISPLAY INVISIBLE (-8675 4750);
FORCEPROP 1 LASTPIN (-8725 4550) $PN 1
J 0
(-8713 4562);
DISPLAY 0.489362 (-8713 4562);
FORCEPROP 1 LASTPIN (-8525 4550) $PN 2
J 0
(-8563 4562);
DISPLAY 0.489362 (-8563 4562);
FORCEPROP 1 LAST MATERIAL EMPTY
J 0
(-8300 4550);
DISPLAY 0.489362 (-8300 4550);
PAINT RED (-8300 4550);
FORCEPROP 1 LAST TOLERANCE 5%
J 0
(-8400 4550);
DISPLAY 0.489362 (-8400 4550);
PAINT SKYBLUE (-8400 4550);
FORCEPROP 1 LAST VALUE 10K
J 2
(-8425 4550);
DISPLAY 0.489362 (-8425 4550);
PAINT SKYBLUE (-8425 4550);
FORCEPROP 2 LAST CDS_LIB pure_quanta
J 0
(-8625 4550);
PAINT MONO (-8625 4550);
DISPLAY INVISIBLE (-8625 4550);
FORCEPROP 1 LAST PATH I46
J 0
(-8675 4700);
DISPLAY 0.978723 (-8675 4700);
PAINT WHITE (-8675 4700);
DISPLAY INVISIBLE (-8675 4700);
FORCEPROP 1 LAST WATTAGE 1/16W
J 2
(-8425 4625);
DISPLAY 0.510638 (-8425 4625);
PAINT SKYBLUE (-8425 4625);
DISPLAY INVISIBLE (-8425 4625);
FORCEPROP 1 LAST PART_NUMBER TMP_QCS31002JB28
J 0
(-8725 4600);
DISPLAY 0.510638 (-8725 4600);
PAINT SKYBLUE (-8725 4600);
DISPLAY INVISIBLE (-8725 4600);
FORCEPROP 1 LAST PACK_TYPE 0402LF
J 0
(-8725 4625);
DISPLAY 0.510638 (-8725 4625);
PAINT SKYBLUE (-8725 4625);
DISPLAY INVISIBLE (-8725 4625);
FORCEADD OFFPAGE..2
(-7225 3725);
FORCEPROP 2 LAST $XR3 117 
J 0
(-6766 3725);
DISPLAY 0.638298 (-6766 3725);
PAINT MONO (-6766 3725);
FORCEPROP 2 LAST $XR2 80 
J 0
(-6856 3725);
DISPLAY 0.638298 (-6856 3725);
PAINT MONO (-6856 3725);
FORCEPROP 2 LAST $XR1 75 
J 0
(-6946 3725);
DISPLAY 0.638298 (-6946 3725);
PAINT MONO (-6946 3725);
FORCEPROP 2 LAST $XR0 29 
J 0
(-7036 3725);
DISPLAY 0.638298 (-7036 3725);
PAINT MONO (-7036 3725);
FORCEPROP 2 LAST CDS_LIB standard
J 0
(-7225 3725);
DISPLAY INVISIBLE (-7225 3725);
FORCEPROP 1 LAST OFFPAGE TRUE
J 0
(-6900 3600);
DISPLAY 0.872340 (-6900 3600);
PAINT GREEN (-6900 3600);
DISPLAY INVISIBLE (-6900 3600);
FORCEPROP 1 LAST COMMENT_BODY TRUE
J 0
(-7270 3630);
DISPLAY 0.872340 (-7270 3630);
PAINT GREEN (-7270 3630);
DISPLAY INVISIBLE (-7270 3630);
FORCEPROP 2 LAST PATH I5
J 0
(-6925 3775);
DISPLAY 1.021277 (-6925 3775);
DISPLAY INVISIBLE (-6925 3775);
FORCEADD OFFPAGE..2
(-7225 3350);
FORCEPROP 2 LAST $XR1 29 
J 0
(-6946 3350);
DISPLAY 0.638298 (-6946 3350);
PAINT MONO (-6946 3350);
FORCEPROP 2 LAST $XR0 75 
J 0
(-7036 3350);
DISPLAY 0.638298 (-7036 3350);
PAINT MONO (-7036 3350);
FORCEPROP 2 LAST PATH I7
J 0
(-6925 3400);
DISPLAY 1.021277 (-6925 3400);
DISPLAY INVISIBLE (-6925 3400);
FORCEPROP 1 LAST COMMENT_BODY TRUE
J 0
(-7270 3255);
DISPLAY 0.872340 (-7270 3255);
PAINT GREEN (-7270 3255);
DISPLAY INVISIBLE (-7270 3255);
FORCEPROP 1 LAST OFFPAGE TRUE
J 0
(-6900 3225);
DISPLAY 0.872340 (-6900 3225);
PAINT GREEN (-6900 3225);
DISPLAY INVISIBLE (-6900 3225);
FORCEPROP 2 LAST CDS_LIB standard
J 0
(-7225 3350);
DISPLAY INVISIBLE (-7225 3350);
FORCEADD Q_RES..1
(-8650 3725);
FORCEPROP 1 LAST LOCATION R750
J 0
(-8875 3725);
DISPLAY 0.489362 (-8875 3725);
PAINT SKYBLUE (-8875 3725);
FORCEPROP 0 LAST $SEC 1
J 0
(-8325 3750);
DISPLAY 0.680851 (-8325 3750);
PAINT MONO (-8325 3750);
DISPLAY INVISIBLE (-8325 3750);
FORCEPROP 0 LAST CDS_SEC 1
J 0
(-8325 3750);
DISPLAY 0.680851 (-8325 3750);
DISPLAY INVISIBLE (-8325 3750);
FORCEPROP 1 LASTPIN (-8750 3725) $PN 1
J 0
(-8738 3737);
DISPLAY 0.489362 (-8738 3737);
PAINT MONO (-8738 3737);
FORCEPROP 1 LASTPIN (-8550 3725) $PN 2
J 0
(-8588 3737);
DISPLAY 0.489362 (-8588 3737);
PAINT MONO (-8588 3737);
FORCEPROP 1 LAST MATERIAL CHIP
J 0
(-8325 3725);
DISPLAY 0.489362 (-8325 3725);
PAINT SKYBLUE (-8325 3725);
FORCEPROP 1 LAST TOLERANCE 1%
J 0
(-8425 3725);
DISPLAY 0.489362 (-8425 3725);
PAINT SKYBLUE (-8425 3725);
FORCEPROP 1 LAST VALUE 30K
J 2
(-8475 3725);
DISPLAY 0.489362 (-8475 3725);
PAINT SKYBLUE (-8475 3725);
FORCEPROP 2 LAST CDS_LIB pure_quanta
J 0
(-8650 3725);
DISPLAY INVISIBLE (-8650 3725);
FORCEPROP 1 LAST PATH I74
J 0
(-8700 3875);
DISPLAY 0.978723 (-8700 3875);
PAINT WHITE (-8700 3875);
DISPLAY INVISIBLE (-8700 3875);
FORCEPROP 1 LAST WATTAGE 1/16W
J 2
(-8450 3800);
DISPLAY 0.510638 (-8450 3800);
PAINT SKYBLUE (-8450 3800);
DISPLAY INVISIBLE (-8450 3800);
FORCEPROP 1 LAST PART_NUMBER CS33002FB13
J 0
(-8750 3775);
DISPLAY 0.510638 (-8750 3775);
PAINT SKYBLUE (-8750 3775);
DISPLAY INVISIBLE (-8750 3775);
FORCEPROP 1 LAST PACK_TYPE 0402LF
J 0
(-8750 3800);
DISPLAY 0.510638 (-8750 3800);
PAINT SKYBLUE (-8750 3800);
DISPLAY INVISIBLE (-8750 3800);
FORCEADD Q_RES..1
(-8650 3350);
FORCEPROP 1 LAST LOCATION R753
J 0
(-8875 3350);
DISPLAY 0.489362 (-8875 3350);
PAINT SKYBLUE (-8875 3350);
FORCEPROP 0 LAST $SEC 1
J 0
(-8325 3375);
DISPLAY 0.680851 (-8325 3375);
PAINT MONO (-8325 3375);
DISPLAY INVISIBLE (-8325 3375);
FORCEPROP 0 LAST CDS_SEC 1
J 0
(-8325 3375);
DISPLAY 0.680851 (-8325 3375);
DISPLAY INVISIBLE (-8325 3375);
FORCEPROP 1 LASTPIN (-8750 3350) $PN 1
J 0
(-8738 3362);
DISPLAY 0.489362 (-8738 3362);
PAINT MONO (-8738 3362);
FORCEPROP 1 LASTPIN (-8550 3350) $PN 2
J 0
(-8588 3362);
DISPLAY 0.489362 (-8588 3362);
PAINT MONO (-8588 3362);
FORCEPROP 1 LAST MATERIAL CHIP
J 0
(-8325 3350);
DISPLAY 0.489362 (-8325 3350);
PAINT SKYBLUE (-8325 3350);
FORCEPROP 1 LAST TOLERANCE 5%
J 0
(-8425 3350);
DISPLAY 0.489362 (-8425 3350);
PAINT SKYBLUE (-8425 3350);
FORCEPROP 1 LAST VALUE 10K
J 2
(-8475 3350);
DISPLAY 0.489362 (-8475 3350);
PAINT SKYBLUE (-8475 3350);
FORCEPROP 2 LAST CDS_LIB pure_quanta
J 0
(-8650 3350);
DISPLAY INVISIBLE (-8650 3350);
FORCEPROP 1 LAST PATH I75
J 0
(-8700 3500);
DISPLAY 0.978723 (-8700 3500);
PAINT WHITE (-8700 3500);
DISPLAY INVISIBLE (-8700 3500);
FORCEPROP 1 LAST WATTAGE 1/16W
J 2
(-8450 3425);
DISPLAY 0.510638 (-8450 3425);
PAINT SKYBLUE (-8450 3425);
DISPLAY INVISIBLE (-8450 3425);
FORCEPROP 1 LAST PART_NUMBER TMP_QCS31002JB28
J 0
(-8750 3400);
DISPLAY 0.510638 (-8750 3400);
PAINT SKYBLUE (-8750 3400);
DISPLAY INVISIBLE (-8750 3400);
FORCEPROP 1 LAST PACK_TYPE 0402LF
J 0
(-8750 3425);
DISPLAY 0.510638 (-8750 3425);
PAINT SKYBLUE (-8750 3425);
DISPLAY INVISIBLE (-8750 3425);
FORCEADD Q_RES..1
(-8650 4250);
FORCEPROP 1 LAST LOCATION R747
J 0
(-8875 4250);
DISPLAY 0.489362 (-8875 4250);
PAINT SKYBLUE (-8875 4250);
FORCEPROP 2 LAST $SEC 1
J 0
(-8700 4450);
DISPLAY 0.680851 (-8700 4450);
PAINT MONO (-8700 4450);
DISPLAY INVISIBLE (-8700 4450);
FORCEPROP 2 LAST CDS_SEC 1
J 0
(-8700 4450);
DISPLAY 1.021277 (-8700 4450);
DISPLAY INVISIBLE (-8700 4450);
FORCEPROP 1 LASTPIN (-8750 4250) $PN 1
J 0
(-8738 4262);
DISPLAY 0.489362 (-8738 4262);
FORCEPROP 1 LASTPIN (-8550 4250) $PN 2
J 0
(-8588 4262);
DISPLAY 0.489362 (-8588 4262);
FORCEPROP 1 LAST MATERIAL CHIP
J 0
(-8325 4250);
DISPLAY 0.489362 (-8325 4250);
PAINT SKYBLUE (-8325 4250);
FORCEPROP 1 LAST TOLERANCE 5%
J 0
(-8425 4250);
DISPLAY 0.489362 (-8425 4250);
PAINT SKYBLUE (-8425 4250);
FORCEPROP 1 LAST VALUE 1K
J 2
(-8450 4250);
DISPLAY 0.489362 (-8450 4250);
PAINT SKYBLUE (-8450 4250);
FORCEPROP 2 LAST CDS_LIB pure_quanta
J 0
(-8650 4250);
PAINT MONO (-8650 4250);
DISPLAY INVISIBLE (-8650 4250);
FORCEPROP 1 LAST PATH I8
J 0
(-8700 4400);
DISPLAY 0.978723 (-8700 4400);
PAINT WHITE (-8700 4400);
DISPLAY INVISIBLE (-8700 4400);
FORCEPROP 1 LAST WATTAGE 1/16W
J 2
(-8475 4325);
DISPLAY 0.510638 (-8475 4325);
PAINT SKYBLUE (-8475 4325);
DISPLAY INVISIBLE (-8475 4325);
FORCEPROP 1 LAST PART_NUMBER TMP_QCS21002JB34
J 0
(-8750 4300);
DISPLAY 0.510638 (-8750 4300);
PAINT SKYBLUE (-8750 4300);
DISPLAY INVISIBLE (-8750 4300);
FORCEPROP 1 LAST PACK_TYPE 0402LF
J 0
(-8750 4325);
DISPLAY 0.510638 (-8750 4325);
PAINT SKYBLUE (-8750 4325);
DISPLAY INVISIBLE (-8750 4325);
FORCEADD OFFPAGE..2
(-2525 5550);
FORCEPROP 2 LAST $XR1 75 
J 0
(-2246 5550);
DISPLAY 0.638298 (-2246 5550);
PAINT MONO (-2246 5550);
FORCEPROP 2 LAST $XR0 56 
J 0
(-2336 5550);
DISPLAY 0.638298 (-2336 5550);
PAINT MONO (-2336 5550);
FORCEPROP 1 LAST COMMENT_BODY TRUE
J 0
(-2570 5455);
DISPLAY 0.872340 (-2570 5455);
PAINT GREEN (-2570 5455);
DISPLAY INVISIBLE (-2570 5455);
FORCEPROP 1 LAST OFFPAGE TRUE
J 0
(-2200 5425);
DISPLAY 0.872340 (-2200 5425);
PAINT GREEN (-2200 5425);
DISPLAY INVISIBLE (-2200 5425);
FORCEPROP 2 LAST CDS_LIB standard
J 0
(-2525 5550);
DISPLAY INVISIBLE (-2525 5550);
FORCEPROP 2 LAST PATH I80
J 0
(-2325 5600);
DISPLAY 0.680851 (-2325 5600);
DISPLAY INVISIBLE (-2325 5600);
FORCEADD OFFPAGE..2
(-2525 5275);
FORCEPROP 2 LAST $XR1 56 
J 0
(-2246 5275);
DISPLAY 0.638298 (-2246 5275);
PAINT MONO (-2246 5275);
FORCEPROP 2 LAST $XR0 75 
J 0
(-2336 5275);
DISPLAY 0.638298 (-2336 5275);
PAINT MONO (-2336 5275);
FORCEPROP 1 LAST COMMENT_BODY TRUE
J 0
(-2570 5180);
DISPLAY 0.872340 (-2570 5180);
PAINT GREEN (-2570 5180);
DISPLAY INVISIBLE (-2570 5180);
FORCEPROP 1 LAST OFFPAGE TRUE
J 0
(-2200 5150);
DISPLAY 0.872340 (-2200 5150);
PAINT GREEN (-2200 5150);
DISPLAY INVISIBLE (-2200 5150);
FORCEPROP 2 LAST CDS_LIB standard
J 0
(-2525 5275);
DISPLAY INVISIBLE (-2525 5275);
FORCEPROP 2 LAST PATH I81
J 0
(-2225 5325);
DISPLAY 0.680851 (-2225 5325);
DISPLAY INVISIBLE (-2225 5325);
FORCEADD OFFPAGE..2
(-2525 5000);
FORCEPROP 2 LAST $XR1 75 
J 0
(-2246 5000);
DISPLAY 0.638298 (-2246 5000);
PAINT MONO (-2246 5000);
FORCEPROP 2 LAST $XR0 55 
J 0
(-2336 5000);
DISPLAY 0.638298 (-2336 5000);
PAINT MONO (-2336 5000);
FORCEPROP 1 LAST COMMENT_BODY TRUE
J 0
(-2570 4905);
DISPLAY 0.872340 (-2570 4905);
PAINT GREEN (-2570 4905);
DISPLAY INVISIBLE (-2570 4905);
FORCEPROP 1 LAST OFFPAGE TRUE
J 0
(-2200 4875);
DISPLAY 0.872340 (-2200 4875);
PAINT GREEN (-2200 4875);
DISPLAY INVISIBLE (-2200 4875);
FORCEPROP 2 LAST CDS_LIB standard
J 0
(-2525 5000);
DISPLAY INVISIBLE (-2525 5000);
FORCEPROP 2 LAST PATH I82
J 0
(-2225 5050);
DISPLAY 0.680851 (-2225 5050);
DISPLAY INVISIBLE (-2225 5050);
FORCEADD OFFPAGE..2
(-2525 4650);
FORCEPROP 2 LAST $XR1 75 
J 0
(-2246 4650);
DISPLAY 0.638298 (-2246 4650);
PAINT MONO (-2246 4650);
FORCEPROP 2 LAST $XR0 56 
J 0
(-2336 4650);
DISPLAY 0.638298 (-2336 4650);
PAINT MONO (-2336 4650);
FORCEPROP 2 LAST CDS_LIB standard
J 0
(-2525 4650);
DISPLAY INVISIBLE (-2525 4650);
FORCEPROP 1 LAST OFFPAGE TRUE
J 0
(-2200 4525);
DISPLAY 0.872340 (-2200 4525);
PAINT GREEN (-2200 4525);
DISPLAY INVISIBLE (-2200 4525);
FORCEPROP 1 LAST COMMENT_BODY TRUE
J 0
(-2570 4555);
DISPLAY 0.872340 (-2570 4555);
PAINT GREEN (-2570 4555);
DISPLAY INVISIBLE (-2570 4555);
FORCEPROP 2 LAST PATH I83
J 0
(-2325 4700);
DISPLAY 0.680851 (-2325 4700);
DISPLAY INVISIBLE (-2325 4700);
FORCEADD OFFPAGE..2
(-2525 4375);
FORCEPROP 2 LAST $XR1 56 
J 0
(-2246 4375);
DISPLAY 0.638298 (-2246 4375);
PAINT MONO (-2246 4375);
FORCEPROP 2 LAST $XR0 75 
J 0
(-2336 4375);
DISPLAY 0.638298 (-2336 4375);
PAINT MONO (-2336 4375);
FORCEPROP 2 LAST PATH I84
J 0
(-2225 4425);
DISPLAY 0.680851 (-2225 4425);
DISPLAY INVISIBLE (-2225 4425);
FORCEPROP 1 LAST COMMENT_BODY TRUE
J 0
(-2570 4280);
DISPLAY 0.872340 (-2570 4280);
PAINT GREEN (-2570 4280);
DISPLAY INVISIBLE (-2570 4280);
FORCEPROP 1 LAST OFFPAGE TRUE
J 0
(-2200 4250);
DISPLAY 0.872340 (-2200 4250);
PAINT GREEN (-2200 4250);
DISPLAY INVISIBLE (-2200 4250);
FORCEPROP 2 LAST CDS_LIB standard
J 0
(-2525 4375);
DISPLAY INVISIBLE (-2525 4375);
FORCEADD Q_RES..1
(-3950 5550);
FORCEPROP 1 LAST LOCATION R730
J 0
(-4000 5600);
DISPLAY 0.489362 (-4000 5600);
PAINT SKYBLUE (-4000 5600);
FORCEPROP 0 LAST $SEC 1
J 0
(-4000 5650);
DISPLAY 0.680851 (-4000 5650);
PAINT MONO (-4000 5650);
DISPLAY INVISIBLE (-4000 5650);
FORCEPROP 0 LAST CDS_SEC 1
J 0
(-4000 5650);
DISPLAY 0.680851 (-4000 5650);
DISPLAY INVISIBLE (-4000 5650);
FORCEPROP 1 LASTPIN (-4050 5550) $PN 1
J 0
(-4038 5562);
DISPLAY 0.489362 (-4038 5562);
PAINT MONO (-4038 5562);
FORCEPROP 1 LASTPIN (-3850 5550) $PN 2
J 0
(-3888 5562);
DISPLAY 0.489362 (-3888 5562);
PAINT MONO (-3888 5562);
FORCEPROP 1 LAST TOLERANCE 5%
J 0
(-3725 5550);
DISPLAY 0.489362 (-3725 5550);
PAINT SKYBLUE (-3725 5550);
FORCEPROP 1 LAST VALUE 10K
J 2
(-3775 5550);
DISPLAY 0.489362 (-3775 5550);
PAINT SKYBLUE (-3775 5550);
FORCEPROP 1 LAST MATERIAL CHIP
J 0
(-3625 5550);
DISPLAY 0.489362 (-3625 5550);
PAINT SKYBLUE (-3625 5550);
FORCEPROP 1 LAST PACK_TYPE 0402LF
J 0
(-4050 5625);
DISPLAY 0.510638 (-4050 5625);
PAINT SKYBLUE (-4050 5625);
DISPLAY INVISIBLE (-4050 5625);
FORCEPROP 1 LAST PART_NUMBER TMP_QCS31002JB28
J 0
(-4050 5600);
DISPLAY 0.510638 (-4050 5600);
PAINT SKYBLUE (-4050 5600);
DISPLAY INVISIBLE (-4050 5600);
FORCEPROP 1 LAST WATTAGE 1/16W
J 2
(-3750 5625);
DISPLAY 0.510638 (-3750 5625);
PAINT SKYBLUE (-3750 5625);
DISPLAY INVISIBLE (-3750 5625);
FORCEPROP 1 LAST PATH I87
J 0
(-4000 5700);
DISPLAY 0.978723 (-4000 5700);
PAINT WHITE (-4000 5700);
DISPLAY INVISIBLE (-4000 5700);
FORCEPROP 2 LAST CDS_LIB pure_quanta
J 0
(-3950 5550);
DISPLAY INVISIBLE (-3950 5550);
FORCEADD UNIVERSAL_POWER..1
(-4275 5800);
FORCEPROP 3 LASTPIN (-4275 5750) SIG_NAME PVDD18_S5_P1\g
J 0
(-4265 5760);
DISPLAY 0.659574 (-4265 5760);
PAINT MONO (-4265 5760);
DISPLAY INVISIBLE (-4265 5760);
FORCEPROP 1 LAST HDL_POWER PVDD18_S5_P1
J 1
(-4275 5850);
DISPLAY 0.489362 (-4275 5850);
PAINT GREEN (-4275 5850);
FORCEPROP 2 LAST CDS_LIB pure_quanta_power
J 0
(-4275 5800);
DISPLAY INVISIBLE (-4275 5800);
FORCEPROP 1 LAST PATH I88
J 0
(-4225 5825);
DISPLAY 0.872340 (-4225 5825);
PAINT AQUA (-4225 5825);
DISPLAY INVISIBLE (-4225 5825);
FORCEADD Q_RES..1
(-3975 5275);
FORCEPROP 1 LAST LOCATION R736
J 0
(-4200 5275);
DISPLAY 0.489362 (-4200 5275);
PAINT SKYBLUE (-4200 5275);
FORCEPROP 2 LAST $SEC 1
J 0
(-4025 5475);
DISPLAY 0.680851 (-4025 5475);
PAINT MONO (-4025 5475);
DISPLAY INVISIBLE (-4025 5475);
FORCEPROP 2 LAST CDS_SEC 1
J 0
(-4025 5475);
DISPLAY 1.021277 (-4025 5475);
DISPLAY INVISIBLE (-4025 5475);
FORCEPROP 1 LASTPIN (-4075 5275) $PN 1
J 0
(-4063 5287);
DISPLAY 0.489362 (-4063 5287);
FORCEPROP 1 LASTPIN (-3875 5275) $PN 2
J 0
(-3913 5287);
DISPLAY 0.489362 (-3913 5287);
FORCEPROP 1 LAST TOLERANCE 5%
J 0
(-3750 5275);
DISPLAY 0.489362 (-3750 5275);
PAINT SKYBLUE (-3750 5275);
FORCEPROP 1 LAST VALUE 10K
J 2
(-3775 5275);
DISPLAY 0.489362 (-3775 5275);
PAINT SKYBLUE (-3775 5275);
FORCEPROP 1 LAST MATERIAL EMPTY
J 0
(-3650 5275);
DISPLAY 0.489362 (-3650 5275);
PAINT RED (-3650 5275);
FORCEPROP 2 LAST CDS_LIB pure_quanta
J 0
(-3975 5275);
PAINT MONO (-3975 5275);
DISPLAY INVISIBLE (-3975 5275);
FORCEPROP 1 LAST PATH I89
J 0
(-4025 5425);
DISPLAY 0.978723 (-4025 5425);
PAINT WHITE (-4025 5425);
DISPLAY INVISIBLE (-4025 5425);
FORCEPROP 1 LAST WATTAGE 1/16W
J 2
(-3775 5350);
DISPLAY 0.510638 (-3775 5350);
PAINT SKYBLUE (-3775 5350);
DISPLAY INVISIBLE (-3775 5350);
FORCEPROP 1 LAST PART_NUMBER TMP_QCS31002JB28
J 0
(-4075 5325);
DISPLAY 0.510638 (-4075 5325);
PAINT SKYBLUE (-4075 5325);
DISPLAY INVISIBLE (-4075 5325);
FORCEPROP 1 LAST PACK_TYPE 0402LF
J 0
(-4075 5350);
DISPLAY 0.510638 (-4075 5350);
PAINT SKYBLUE (-4075 5350);
DISPLAY INVISIBLE (-4075 5350);
FORCEADD Q_RES..1
(-8650 3975);
FORCEPROP 1 LAST LOCATION R748
J 0
(-8875 3975);
DISPLAY 0.489362 (-8875 3975);
PAINT SKYBLUE (-8875 3975);
FORCEPROP 2 LAST $SEC 1
J 0
(-8700 4175);
DISPLAY 0.680851 (-8700 4175);
PAINT MONO (-8700 4175);
DISPLAY INVISIBLE (-8700 4175);
FORCEPROP 2 LAST CDS_SEC 1
J 0
(-8700 4175);
DISPLAY 1.021277 (-8700 4175);
DISPLAY INVISIBLE (-8700 4175);
FORCEPROP 1 LASTPIN (-8750 3975) $PN 1
J 0
(-8738 3987);
DISPLAY 0.489362 (-8738 3987);
FORCEPROP 1 LASTPIN (-8550 3975) $PN 2
J 0
(-8588 3987);
DISPLAY 0.489362 (-8588 3987);
FORCEPROP 1 LAST MATERIAL EMPTY
J 0
(-8325 3975);
DISPLAY 0.489362 (-8325 3975);
PAINT RED (-8325 3975);
FORCEPROP 1 LAST TOLERANCE 5%
J 0
(-8425 3975);
DISPLAY 0.489362 (-8425 3975);
PAINT SKYBLUE (-8425 3975);
FORCEPROP 1 LAST VALUE 10K
J 2
(-8450 3975);
DISPLAY 0.489362 (-8450 3975);
PAINT SKYBLUE (-8450 3975);
FORCEPROP 2 LAST CDS_LIB pure_quanta
J 0
(-8650 3975);
PAINT MONO (-8650 3975);
DISPLAY INVISIBLE (-8650 3975);
FORCEPROP 1 LAST PATH I9
J 0
(-8700 4125);
DISPLAY 0.978723 (-8700 4125);
PAINT WHITE (-8700 4125);
DISPLAY INVISIBLE (-8700 4125);
FORCEPROP 1 LAST WATTAGE 1/16W
J 2
(-8475 4050);
DISPLAY 0.510638 (-8475 4050);
PAINT SKYBLUE (-8475 4050);
DISPLAY INVISIBLE (-8475 4050);
FORCEPROP 1 LAST PART_NUMBER TMP_QCS31002JB28
J 0
(-8750 4025);
DISPLAY 0.510638 (-8750 4025);
PAINT SKYBLUE (-8750 4025);
DISPLAY INVISIBLE (-8750 4025);
FORCEPROP 1 LAST PACK_TYPE 0402LF
J 0
(-8750 4050);
DISPLAY 0.510638 (-8750 4050);
PAINT SKYBLUE (-8750 4050);
DISPLAY INVISIBLE (-8750 4050);
FORCEADD Q_RES..1
(-3950 5000);
FORCEPROP 1 LAST LOCATION R1501
J 0
(-4200 5000);
DISPLAY 0.489362 (-4200 5000);
PAINT SKYBLUE (-4200 5000);
FORCEPROP 2 LAST $SEC 1
J 0
(-4000 5200);
DISPLAY 0.680851 (-4000 5200);
PAINT MONO (-4000 5200);
DISPLAY INVISIBLE (-4000 5200);
FORCEPROP 2 LAST CDS_SEC 1
J 0
(-4000 5200);
DISPLAY 1.021277 (-4000 5200);
DISPLAY INVISIBLE (-4000 5200);
FORCEPROP 1 LASTPIN (-4050 5000) $PN 1
J 0
(-4038 5012);
DISPLAY 0.489362 (-4038 5012);
FORCEPROP 1 LASTPIN (-3850 5000) $PN 2
J 0
(-3888 5012);
DISPLAY 0.489362 (-3888 5012);
FORCEPROP 1 LAST MATERIAL EMPTY
J 0
(-3625 5000);
DISPLAY 0.489362 (-3625 5000);
PAINT RED (-3625 5000);
FORCEPROP 1 LAST TOLERANCE 5%
J 0
(-3725 5000);
DISPLAY 0.489362 (-3725 5000);
PAINT SKYBLUE (-3725 5000);
FORCEPROP 1 LAST VALUE 10K
J 2
(-3750 5000);
DISPLAY 0.489362 (-3750 5000);
PAINT SKYBLUE (-3750 5000);
FORCEPROP 2 LAST CDS_LIB pure_quanta
J 0
(-3950 5000);
PAINT MONO (-3950 5000);
DISPLAY INVISIBLE (-3950 5000);
FORCEPROP 1 LAST PATH I90
J 0
(-4000 5150);
DISPLAY 0.978723 (-4000 5150);
PAINT WHITE (-4000 5150);
DISPLAY INVISIBLE (-4000 5150);
FORCEPROP 1 LAST WATTAGE 1/16W
J 2
(-3775 5075);
DISPLAY 0.510638 (-3775 5075);
PAINT SKYBLUE (-3775 5075);
DISPLAY INVISIBLE (-3775 5075);
FORCEPROP 1 LAST PART_NUMBER TMP_QCS31002JB28
J 0
(-4050 5050);
DISPLAY 0.510638 (-4050 5050);
PAINT SKYBLUE (-4050 5050);
DISPLAY INVISIBLE (-4050 5050);
FORCEPROP 1 LAST PACK_TYPE 0402LF
J 0
(-4050 5075);
DISPLAY 0.510638 (-4050 5075);
PAINT SKYBLUE (-4050 5075);
DISPLAY INVISIBLE (-4050 5075);
FORCEADD Q_RES..1
(-3925 4650);
FORCEPROP 1 LAST LOCATION R754
J 0
(-4150 4650);
DISPLAY 0.489362 (-4150 4650);
PAINT SKYBLUE (-4150 4650);
FORCEPROP 2 LAST $SEC 1
J 0
(-3975 4850);
DISPLAY 0.680851 (-3975 4850);
PAINT MONO (-3975 4850);
DISPLAY INVISIBLE (-3975 4850);
FORCEPROP 2 LAST CDS_SEC 1
J 0
(-3975 4850);
DISPLAY 1.021277 (-3975 4850);
DISPLAY INVISIBLE (-3975 4850);
FORCEPROP 1 LASTPIN (-4025 4650) $PN 1
J 0
(-4013 4662);
DISPLAY 0.489362 (-4013 4662);
FORCEPROP 1 LASTPIN (-3825 4650) $PN 2
J 0
(-3863 4662);
DISPLAY 0.489362 (-3863 4662);
FORCEPROP 1 LAST PACK_TYPE 0402LF
J 0
(-4025 4725);
DISPLAY 0.489362 (-4025 4725);
PAINT SKYBLUE (-4025 4725);
FORCEPROP 1 LAST PART_NUMBER TMP_QCS31002JB28
J 0
(-4025 4700);
DISPLAY 0.489362 (-4025 4700);
PAINT SKYBLUE (-4025 4700);
FORCEPROP 1 LAST VALUE 10K
J 2
(-3725 4650);
DISPLAY 0.489362 (-3725 4650);
PAINT SKYBLUE (-3725 4650);
FORCEPROP 1 LAST TOLERANCE 5%
J 0
(-3700 4650);
DISPLAY 0.489362 (-3700 4650);
PAINT SKYBLUE (-3700 4650);
FORCEPROP 1 LAST WATTAGE 1/16W
J 2
(-3750 4725);
DISPLAY 0.489362 (-3750 4725);
PAINT SKYBLUE (-3750 4725);
FORCEPROP 1 LAST MATERIAL EMPTY
J 0
(-3600 4650);
DISPLAY 0.489362 (-3600 4650);
PAINT RED (-3600 4650);
FORCEPROP 1 LAST PATH I91
J 0
(-3975 4800);
DISPLAY 0.978723 (-3975 4800);
PAINT WHITE (-3975 4800);
DISPLAY INVISIBLE (-3975 4800);
FORCEPROP 2 LAST CDS_LIB pure_quanta
J 0
(-3925 4650);
PAINT MONO (-3925 4650);
DISPLAY INVISIBLE (-3925 4650);
FORCEADD Q_RES..1
(-3950 4375);
FORCEPROP 1 LAST LOCATION R760
J 0
(-4175 4375);
DISPLAY 0.489362 (-4175 4375);
PAINT SKYBLUE (-4175 4375);
FORCEPROP 0 LAST $SEC 1
J 0
(-4175 4425);
DISPLAY 0.680851 (-4175 4425);
PAINT MONO (-4175 4425);
DISPLAY INVISIBLE (-4175 4425);
FORCEPROP 0 LAST CDS_SEC 1
J 0
(-4175 4425);
DISPLAY 0.680851 (-4175 4425);
DISPLAY INVISIBLE (-4175 4425);
FORCEPROP 1 LASTPIN (-4050 4375) $PN 1
J 0
(-4038 4387);
DISPLAY 0.489362 (-4038 4387);
PAINT MONO (-4038 4387);
FORCEPROP 1 LASTPIN (-3850 4375) $PN 2
J 0
(-3888 4387);
DISPLAY 0.489362 (-3888 4387);
PAINT MONO (-3888 4387);
FORCEPROP 1 LAST MATERIAL CHIP
J 0
(-3625 4375);
DISPLAY 0.489362 (-3625 4375);
PAINT SKYBLUE (-3625 4375);
FORCEPROP 1 LAST TOLERANCE 5%
J 0
(-3725 4375);
DISPLAY 0.489362 (-3725 4375);
PAINT SKYBLUE (-3725 4375);
FORCEPROP 1 LAST VALUE 10K
J 2
(-3775 4375);
DISPLAY 0.489362 (-3775 4375);
PAINT SKYBLUE (-3775 4375);
FORCEPROP 2 LAST CDS_LIB pure_quanta
J 0
(-3950 4375);
DISPLAY INVISIBLE (-3950 4375);
FORCEPROP 1 LAST PATH I92
J 0
(-4000 4525);
DISPLAY 0.978723 (-4000 4525);
PAINT WHITE (-4000 4525);
DISPLAY INVISIBLE (-4000 4525);
FORCEPROP 1 LAST WATTAGE 1/16W
J 2
(-3750 4450);
DISPLAY 0.510638 (-3750 4450);
PAINT SKYBLUE (-3750 4450);
DISPLAY INVISIBLE (-3750 4450);
FORCEPROP 1 LAST PART_NUMBER TMP_QCS31002JB28
J 0
(-4050 4425);
DISPLAY 0.510638 (-4050 4425);
PAINT SKYBLUE (-4050 4425);
DISPLAY INVISIBLE (-4050 4425);
FORCEPROP 1 LAST PACK_TYPE 0402LF
J 0
(-4050 4450);
DISPLAY 0.510638 (-4050 4450);
PAINT SKYBLUE (-4050 4450);
DISPLAY INVISIBLE (-4050 4450);
FORCEADD OFFPAGE..2
(-2525 4100);
FORCEPROP 2 LAST $XR1 75 
J 0
(-2246 4100);
DISPLAY 0.638298 (-2246 4100);
PAINT MONO (-2246 4100);
FORCEPROP 2 LAST $XR0 55 
J 0
(-2336 4100);
DISPLAY 0.638298 (-2336 4100);
PAINT MONO (-2336 4100);
FORCEPROP 2 LAST CDS_LIB standard
J 0
(-2525 4100);
DISPLAY INVISIBLE (-2525 4100);
FORCEPROP 1 LAST OFFPAGE TRUE
J 0
(-2200 3975);
DISPLAY 0.872340 (-2200 3975);
PAINT GREEN (-2200 3975);
DISPLAY INVISIBLE (-2200 3975);
FORCEPROP 1 LAST COMMENT_BODY TRUE
J 0
(-2570 4005);
DISPLAY 0.872340 (-2570 4005);
PAINT GREEN (-2570 4005);
DISPLAY INVISIBLE (-2570 4005);
FORCEPROP 2 LAST PATH I93
J 0
(-2225 4150);
DISPLAY 0.680851 (-2225 4150);
DISPLAY INVISIBLE (-2225 4150);
FORCEADD Q_RES..1
(-3950 4100);
FORCEPROP 1 LAST LOCATION R1502
J 0
(-4175 4100);
DISPLAY 0.489362 (-4175 4100);
PAINT SKYBLUE (-4175 4100);
FORCEPROP 2 LAST $SEC 1
J 0
(-4000 4300);
DISPLAY 0.680851 (-4000 4300);
PAINT MONO (-4000 4300);
DISPLAY INVISIBLE (-4000 4300);
FORCEPROP 2 LAST CDS_SEC 1
J 0
(-4000 4300);
DISPLAY 1.021277 (-4000 4300);
DISPLAY INVISIBLE (-4000 4300);
FORCEPROP 1 LASTPIN (-4050 4100) $PN 1
J 0
(-4038 4112);
DISPLAY 0.489362 (-4038 4112);
FORCEPROP 1 LASTPIN (-3850 4100) $PN 2
J 0
(-3888 4112);
DISPLAY 0.489362 (-3888 4112);
FORCEPROP 1 LAST MATERIAL CHIP
J 0
(-3625 4100);
DISPLAY 0.489362 (-3625 4100);
PAINT SKYBLUE (-3625 4100);
FORCEPROP 1 LAST TOLERANCE 5%
J 0
(-3725 4100);
DISPLAY 0.489362 (-3725 4100);
PAINT SKYBLUE (-3725 4100);
FORCEPROP 1 LAST VALUE 10K
J 2
(-3750 4100);
DISPLAY 0.489362 (-3750 4100);
PAINT SKYBLUE (-3750 4100);
FORCEPROP 2 LAST CDS_LIB pure_quanta
J 0
(-3950 4100);
PAINT MONO (-3950 4100);
DISPLAY INVISIBLE (-3950 4100);
FORCEPROP 1 LAST PATH I94
J 0
(-4000 4250);
DISPLAY 0.978723 (-4000 4250);
PAINT WHITE (-4000 4250);
DISPLAY INVISIBLE (-4000 4250);
FORCEPROP 1 LAST WATTAGE 1/16W
J 2
(-3775 4175);
DISPLAY 0.510638 (-3775 4175);
PAINT SKYBLUE (-3775 4175);
DISPLAY INVISIBLE (-3775 4175);
FORCEPROP 1 LAST PART_NUMBER TMP_QCS31002JB28
J 0
(-4050 4150);
DISPLAY 0.510638 (-4050 4150);
PAINT SKYBLUE (-4050 4150);
DISPLAY INVISIBLE (-4050 4150);
FORCEPROP 1 LAST PACK_TYPE 0402LF
J 0
(-4050 4175);
DISPLAY 0.510638 (-4050 4175);
PAINT SKYBLUE (-4050 4175);
DISPLAY INVISIBLE (-4050 4175);
FORCEADD UNIVERSAL_GND..1
(-4275 3725);
FORCEPROP 3 LASTPIN (-4275 3775) SIG_NAME GND\g
J 0
(-4265 3785);
DISPLAY 0.659574 (-4265 3785);
PAINT MONO (-4265 3785);
DISPLAY INVISIBLE (-4265 3785);
FORCEPROP 2 LAST CDS_LIB pure_quanta_power
J 0
(-4275 3725);
DISPLAY INVISIBLE (-4275 3725);
FORCEPROP 1 LAST PATH I95
J 0
(-4200 3725);
DISPLAY 0.872340 (-4200 3725);
PAINT AQUA (-4200 3725);
DISPLAY INVISIBLE (-4200 3725);
FORCEPROP 1 LAST HDL_POWER GND
J 1
(-4250 3650);
DISPLAY 0.872340 (-4250 3650);
PAINT GREEN (-4250 3650);
DISPLAY INVISIBLE (-4250 3650);
FORCEADD DNS..2
(-8600 4925);
PAINT RED (-8600 4925);
FORCEPROP 2 LAST CDS_LIB mstr_misc
J 0
(-8600 4925);
PAINT MONO (-8600 4925);
DISPLAY INVISIBLE (-8600 4925);
FORCEPROP 1 LAST COMMENT_BODY TRUE
R 1
J 0
(-8525 4700);
DISPLAY 0.872340 (-8525 4700);
PAINT GREEN (-8525 4700);
DISPLAY INVISIBLE (-8525 4700);
FORCEADD DNS..2
(-8600 3975);
PAINT RED (-8600 3975);
FORCEPROP 2 LAST CDS_LIB mstr_misc
J 0
(-8600 3975);
PAINT MONO (-8600 3975);
DISPLAY INVISIBLE (-8600 3975);
FORCEPROP 1 LAST COMMENT_BODY TRUE
R 1
J 0
(-8525 3750);
DISPLAY 0.872340 (-8525 3750);
PAINT GREEN (-8525 3750);
DISPLAY INVISIBLE (-8525 3750);
FORCEADD DNS..2
(-3950 5275);
PAINT RED (-3950 5275);
FORCEPROP 2 LAST CDS_LIB mstr_misc
J 0
(-3950 5275);
DISPLAY INVISIBLE (-3950 5275);
FORCEPROP 1 LAST COMMENT_BODY TRUE
R 1
J 0
(-3875 5050);
DISPLAY 0.872340 (-3875 5050);
PAINT GREEN (-3875 5050);
DISPLAY INVISIBLE (-3875 5050);
FORCEADD DNS..2
(-8650 5475);
PAINT RED (-8650 5475);
FORCEPROP 2 LAST CDS_LIB mstr_misc
J 0
(-8650 5475);
PAINT MONO (-8650 5475);
DISPLAY INVISIBLE (-8650 5475);
FORCEPROP 1 LAST COMMENT_BODY TRUE
R 1
J 0
(-8575 5250);
DISPLAY 0.872340 (-8575 5250);
PAINT GREEN (-8575 5250);
DISPLAY INVISIBLE (-8575 5250);
FORCEADD DNS..2
(-8600 4800);
PAINT RED (-8600 4800);
FORCEPROP 2 LAST CDS_LIB mstr_misc
J 0
(-8600 4800);
PAINT MONO (-8600 4800);
DISPLAY INVISIBLE (-8600 4800);
FORCEPROP 1 LAST COMMENT_BODY TRUE
R 1
J 0
(-8525 4575);
DISPLAY 0.872340 (-8525 4575);
PAINT GREEN (-8525 4575);
DISPLAY INVISIBLE (-8525 4575);
FORCEADD QUANTA_TITLE_BLOCK_C..1
(0 0);
FORCEPROP 0 LAST CDS_CON_LAST_MODIFIED Fri Mar 11 14:52:48 2022
J 0
(-1885 15);
DISPLAY INVISIBLE (-1885 15);
FORCEPROP 1 LAST CUSTOM_TXT_CDS <CON_LAST_MODIFIED>
J 0
(-1885 15);
DISPLAY 0.978723 (-1885 15);
FORCEPROP 2 LAST CUSTOM_TXT_CDS <XR_PAGE_TITLE>
J 0
(-7890 5250);
DISPLAY 0.638298 (-7890 5250);
PAINT PINK (-7890 5250);
DISPLAY INVISIBLE (-7890 5250);
FORCEPROP 1 LAST CUSTOM_TXT_CDS <NAME_2>
J 0
(-3175 50);
FORCEPROP 1 LAST CUSTOM_TXT_CDS <NAME_1>
J 0
(-3175 175);
FORCEPROP 1 LAST CUSTOM_TXT_CDS <Q_NUMBER>
J 0
(-1403 103);
DISPLAY 1.212766 (-1403 103);
FORCEPROP 1 LAST CUSTOM_TXT_CDS <Q_PROJ>
J 0
(-2382 102);
DISPLAY 1.212766 (-2382 102);
FORCEPROP 1 LAST CUSTOM_TXT_CDS <Q_REV>
J 0
(-184 103);
DISPLAY 1.212766 (-184 103);
FORCEPROP 1 LAST CUSTOM_TXT_CDS <CON_PAGE_NUM> OF <CON_TOTAL_PAGES>
J 0
(-446 18);
DISPLAY 0.978723 (-446 18);
FORCEPROP 1 LAST Q_DEPT BU9
J 1
(-3763 49);
DISPLAY 1.957447 (-3763 49);
PAINT GREEN (-3763 49);
FORCEPROP 1 LAST Q_TITLE CPU HW STRAP PIN
J 0
(-9300 75);
DISPLAY 2.446809 (-9300 75);
PAINT GREEN (-9300 75);
FORCEPROP 2 LAST PAGE_BORDER TRUE
J 0
(-7890 5250);
DISPLAY 0.638298 (-7890 5250);
PAINT PINK (-7890 5250);
DISPLAY INVISIBLE (-7890 5250);
FORCEPROP 2 LAST CDS_LIB pure_quanta
J 0
(0 0);
DISPLAY INVISIBLE (0 0);
FORCEPROP 1 LAST CDS_LMAN_SYM_OUTLINE -9475,6775,100,-125
J 0
(0 0);
DISPLAY 0.468085 (0 0);
PAINT GREEN (0 0);
DISPLAY INVISIBLE (0 0);
FORCEPROP 1 LAST COMMENT_BODY TRUE
J 0
(12 -13);
DISPLAY 0.978723 (12 -13);
PAINT GREEN (12 -13);
DISPLAY INVISIBLE (12 -13);
FORCEPROP 2 LAST CDS_XR_PAGE_TITLE CR-75 : @T6G_MB_LIB.T6G(SCH_1):PAGE75
J 0
(-7890 5250);
DISPLAY 0.638298 (-7890 5250);
PAINT PINK (-7890 5250);
DISPLAY INVISIBLE (-7890 5250);
FORCEADD DNS..2
(-3900 4650);
PAINT RED (-3900 4650);
FORCEPROP 1 LAST COMMENT_BODY TRUE
R 1
J 0
(-3825 4425);
DISPLAY 0.872340 (-3825 4425);
PAINT GREEN (-3825 4425);
DISPLAY INVISIBLE (-3825 4425);
FORCEPROP 2 LAST CDS_LIB mstr_misc
J 0
(-3900 4650);
DISPLAY INVISIBLE (-3900 4650);
FORCEADD DNS..2
(-3925 5000);
PAINT RED (-3925 5000);
FORCEPROP 2 LAST CDS_LIB mstr_misc
J 0
(-3925 5000);
PAINT MONO (-3925 5000);
DISPLAY INVISIBLE (-3925 5000);
FORCEPROP 1 LAST COMMENT_BODY TRUE
R 1
J 0
(-3850 4775);
DISPLAY 0.872340 (-3850 4775);
PAINT GREEN (-3850 4775);
DISPLAY INVISIBLE (-3850 4775);
FORCEADD DNS..2
(-8600 4550);
PAINT RED (-8600 4550);
FORCEPROP 2 LAST CDS_LIB mstr_misc
J 0
(-8600 4550);
DISPLAY INVISIBLE (-8600 4550);
FORCEPROP 1 LAST COMMENT_BODY TRUE
R 1
J 0
(-8525 4325);
DISPLAY 0.872340 (-8525 4325);
PAINT GREEN (-8525 4325);
DISPLAY INVISIBLE (-8525 4325);
WIRE 16 -1 (-4275 5000)(-4050 5000);
WIRE 16 -1 (-4275 5275)(-4275 5000);
WIRE 16 -1 (-4275 5275)(-4075 5275);
WIRE 16 -1 (-4275 5275)(-4275 5550);
WIRE 16 -1 (-4050 5550)(-4275 5550);
WIRE 16 -1 (-4275 5750)(-4275 5550);
WIRE 16 -1 (-2575 4100)(-3850 4100);
FORCEPROP 2 LAST SIG_NAME CLK_CPU1_RTCCLK
J 0
(-3385 4110);
DISPLAY 0.489362 (-3385 4110);
WIRE 16 -1 (-8550 3350)(-7275 3350);
FORCEPROP 2 LAST SIG_NAME PD_ESPI_CPU0_CLK2
J 0
(-8110 3360);
DISPLAY 0.489362 (-8110 3360);
WIRE 16 -1 (-7275 3725)(-8550 3725);
FORCEPROP 2 LAST SIG_NAME CLK_ESPI_CPU0_CLK1
J 0
(-8110 3735);
DISPLAY 0.489362 (-8110 3735);
WIRE 16 -1 (-7275 3600)(-8550 3600);
FORCEPROP 2 LAST SIG_NAME CLK_CPU0_RTCCLK
J 0
(-8110 3610);
DISPLAY 0.489362 (-8110 3610);
WIRE 16 -1 (-8525 4925)(-7275 4925);
FORCEPROP 2 LAST SIG_NAME CLK_ESPI_CPU0_CLK1
J 0
(-8035 4935);
DISPLAY 0.489362 (-8035 4935);
WIRE 16 -1 (-8525 4800)(-7275 4800);
FORCEPROP 2 LAST SIG_NAME CLK_CPU0_RTCCLK
J 0
(-8035 4810);
DISPLAY 0.489362 (-8035 4810);
WIRE 16 -1 (-8525 4550)(-7275 4550);
FORCEPROP 2 LAST SIG_NAME PD_ESPI_CPU0_CLK2
J 0
(-8035 4560);
DISPLAY 0.489362 (-8035 4560);
WIRE 16 -1 (-8550 3975)(-7275 3975);
FORCEPROP 2 LAST SIG_NAME CPU0_ROM_TYPE_SELECT
J 0
(-8110 3985);
DISPLAY 0.489362 (-8110 3985);
WIRE 16 -1 (-8525 5175)(-7275 5175);
FORCEPROP 2 LAST SIG_NAME CPU0_ROM_TYPE_SELECT
J 0
(-8035 5185);
DISPLAY 0.489362 (-8035 5185);
WIRE 16 -1 (-8550 5450)(-7275 5450);
FORCEPROP 2 LAST SIG_NAME UART_CPU0_SCM_UART1_TX
J 0
(-8060 5460);
DISPLAY 0.489362 (-8060 5460);
WIRE 16 -1 (-8550 4250)(-7275 4250);
FORCEPROP 2 LAST SIG_NAME UART_CPU0_SCM_UART1_TX
J 0
(-8110 4260);
DISPLAY 0.489362 (-8110 4260);
WIRE 16 273 (-8950 2525)(-7925 2525);
WIRE 16 273 (-8950 2325)(-8950 2525);
WIRE 16 273 (-7475 2525)(-7925 2525);
WIRE 16 273 (-7925 2325)(-7925 2525);
WIRE 16 273 (-8950 2325)(-7925 2325);
WIRE 16 273 (-7925 2325)(-7475 2325);
WIRE 16 273 (-7925 2050)(-7925 2325);
WIRE 16 273 (-6275 2525)(-7475 2525);
WIRE 16 273 (-7475 2325)(-7475 2525);
WIRE 16 273 (-8950 2325)(-8950 2050);
WIRE 16 273 (-8950 2050)(-7925 2050);
WIRE 16 273 (-8950 2050)(-8950 1675);
WIRE 16 273 (-7475 2325)(-6275 2325);
WIRE 16 273 (-7475 2325)(-7475 2050);
WIRE 16 273 (-5800 2525)(-6275 2525);
WIRE 16 273 (-6275 2325)(-6275 2525);
WIRE 16 273 (-7925 2050)(-7475 2050);
WIRE 16 273 (-7925 1675)(-7925 2050);
WIRE 16 273 (-8950 1675)(-7925 1675);
WIRE 16 273 (-7925 1675)(-7475 1675);
WIRE 16 273 (-7925 1400)(-7925 1675);
WIRE 16 273 (-6275 2050)(-7475 2050);
WIRE 16 273 (-7475 2050)(-7475 1675);
WIRE 16 273 (-6275 2325)(-5800 2325);
WIRE 16 273 (-6275 2050)(-6275 2325);
WIRE 16 273 (-5800 2525)(-4625 2525);
WIRE 16 273 (-5800 2525)(-5800 2325);
WIRE 16 273 (-8950 1675)(-8950 1400);
WIRE 16 273 (-8950 1400)(-7925 1400);
WIRE 16 273 (-8950 1125)(-8950 1400);
WIRE 16 273 (-4625 2325)(-5800 2325);
WIRE 16 273 (-5800 2050)(-5800 2325);
WIRE 16 273 (-4150 2525)(-4625 2525);
WIRE 16 273 (-4625 2325)(-4625 2525);
WIRE 16 273 (-5800 2050)(-6275 2050);
WIRE 16 273 (-6275 1675)(-6275 2050);
WIRE 16 273 (-6275 1675)(-7475 1675);
WIRE 16 273 (-7475 1675)(-7475 1400);
WIRE 16 273 (-7925 1400)(-7475 1400);
WIRE 16 273 (-7925 1125)(-7925 1400);
WIRE 16 273 (-8950 1125)(-7925 1125);
WIRE 16 273 (-7925 1125)(-7475 1125);
WIRE 16 273 (-7925 1125)(-7925 825);
WIRE 16 273 (-6275 1400)(-7475 1400);
WIRE 16 273 (-7475 1125)(-7475 1400);
WIRE 16 273 (-5800 1675)(-6275 1675);
WIRE 16 273 (-6275 1400)(-6275 1675);
WIRE 16 273 (-4625 2050)(-5800 2050);
WIRE 16 273 (-5800 1675)(-5800 2050);
WIRE 16 273 (-4625 2325)(-4150 2325);
WIRE 16 273 (-4625 2325)(-4625 2050);
WIRE 16 273 (-2175 2525)(-4150 2525);
WIRE 16 273 (-4150 2525)(-4150 2325);
WIRE 16 273 (-8950 1125)(-8950 825);
WIRE 16 273 (-8950 825)(-7925 825);
WIRE 16 273 (-4150 2325)(-2175 2325);
WIRE 16 273 (-4150 2050)(-4150 2325);
WIRE 16 273 (-2175 2325)(-2175 2525);
WIRE 16 273 (-4625 2050)(-4150 2050);
WIRE 16 2730 (-5800 1675)(-4625 2050);
WIRE 16 273 (-4625 1675)(-4625 2050);
WIRE 16 273 (-4625 1675)(-5800 1675);
WIRE 16 273 (-5800 1400)(-5800 1675);
WIRE 16 273 (-5800 1400)(-6275 1400);
WIRE 16 273 (-6275 1125)(-6275 1400);
WIRE 16 273 (-7475 1125)(-7475 825);
WIRE 16 273 (-6275 1125)(-7475 1125);
WIRE 16 273 (-7925 825)(-7475 825);
WIRE 16 273 (-6275 825)(-7475 825);
WIRE 16 273 (-5800 1125)(-6275 1125);
WIRE 16 273 (-6275 1125)(-6275 825);
WIRE 16 2730 (-5800 1400)(-4625 1675);
WIRE 16 273 (-5800 1400)(-4625 1400);
WIRE 16 273 (-5800 1125)(-5800 1400);
WIRE 16 2730 (-4625 1675)(-4150 2050);
WIRE 16 273 (-4625 1675)(-4150 1675);
WIRE 16 273 (-4625 1400)(-4625 1675);
WIRE 16 273 (-4150 2050)(-2175 2050);
WIRE 16 273 (-4150 1675)(-4150 2050);
WIRE 16 273 (-2175 2050)(-2175 2325);
WIRE 16 273 (-2175 1675)(-2175 2050);
WIRE 16 273 (-4150 1675)(-2175 1675);
WIRE 16 273 (-4150 1675)(-4150 1400);
WIRE 16 2730 (-4625 1400)(-4150 1675);
WIRE 16 273 (-4625 1400)(-4150 1400);
WIRE 16 273 (-4625 1400)(-4625 1125);
WIRE 16 273 (-5800 825)(-5800 1125);
WIRE 16 273 (-5800 1125)(-4625 1125);
WIRE 16 273 (-5800 825)(-6275 825);
WIRE 16 273 (-4625 825)(-5800 825);
WIRE 16 273 (-4625 1125)(-4150 1125);
WIRE 16 273 (-4625 1125)(-4625 825);
WIRE 16 273 (-4150 1400)(-2175 1400);
WIRE 16 273 (-4150 1400)(-4150 1125);
WIRE 16 273 (-2175 1400)(-2175 1675);
WIRE 16 273 (-2175 1125)(-2175 1400);
WIRE 16 273 (-4150 825)(-4150 1125);
WIRE 16 273 (-4150 1125)(-2175 1125);
WIRE 16 273 (-4625 825)(-4150 825);
WIRE 16 273 (-2175 825)(-4150 825);
WIRE 16 273 (-2175 825)(-2175 1125);
WIRE 16 -1 (-3850 4375)(-2575 4375);
FORCEPROP 2 LAST SIG_NAME PD_ESPI_CPU1_CLK2
J 0
(-3410 4385);
DISPLAY 0.489362 (-3410 4385);
WIRE 16 -1 (-3825 4650)(-2575 4650);
FORCEPROP 2 LAST SIG_NAME SPI_CPU1_CLK
J 0
(-3385 4660);
DISPLAY 0.489362 (-3385 4660);
WIRE 16 -1 (-3850 5000)(-2575 5000);
FORCEPROP 2 LAST SIG_NAME CLK_CPU1_RTCCLK
J 0
(-3410 5010);
DISPLAY 0.489362 (-3410 5010);
WIRE 16 -1 (-3875 5275)(-2575 5275);
FORCEPROP 2 LAST SIG_NAME PD_ESPI_CPU1_CLK2
J 0
(-3385 5285);
DISPLAY 0.489362 (-3385 5285);
WIRE 16 -1 (-3850 5550)(-2575 5550);
FORCEPROP 2 LAST SIG_NAME SPI_CPU1_CLK
J 0
(-3360 5560);
DISPLAY 0.489362 (-3360 5560);
WIRE 16 -1 (-8950 4250)(-8750 4250);
WIRE 16 -1 (-8950 4250)(-8950 3975);
WIRE 16 -1 (-8950 3975)(-8750 3975);
WIRE 16 -1 (-8950 3725)(-8950 3975);
WIRE 16 -1 (-8950 3725)(-8750 3725);
WIRE 16 -1 (-8950 3725)(-8950 3600);
WIRE 16 -1 (-8950 3350)(-8950 3600);
WIRE 16 -1 (-8950 3600)(-8750 3600);
WIRE 16 -1 (-8950 3350)(-8750 3350);
WIRE 16 -1 (-8950 3350)(-8950 3275);
WIRE 16 -1 (-8950 5450)(-8950 5900);
WIRE 16 -1 (-8950 5450)(-8750 5450);
WIRE 16 -1 (-8950 5450)(-8950 5175);
WIRE 16 -1 (-8950 5175)(-8725 5175);
WIRE 16 -1 (-8950 5175)(-8950 4925);
WIRE 16 -1 (-8950 4925)(-8725 4925);
WIRE 16 -1 (-8950 4800)(-8950 4925);
WIRE 16 -1 (-8950 4800)(-8950 4550);
WIRE 16 -1 (-8950 4800)(-8725 4800);
WIRE 16 -1 (-8950 4550)(-8725 4550);
WIRE 16 -1 (-4275 4100)(-4050 4100);
WIRE 16 -1 (-4275 4375)(-4275 4100);
WIRE 16 -1 (-4275 4100)(-4275 3775);
WIRE 16 -1 (-4275 4375)(-4050 4375);
WIRE 16 -1 (-4275 4375)(-4275 4650);
WIRE 16 -1 (-4275 4650)(-4025 4650);
DOT 1 (-4275 5550);
DOT 1 (-8950 3350);
DOT 1 (-4275 4100);
DOT 1 (-8950 2325);
DOT 1 (-4625 1675);
DOT 1 (-4150 1400);
DOT 1 (-4625 2050);
DOT 1 (-4625 2525);
DOT 1 (-8950 1400);
DOT 1 (-7475 2325);
DOT 1 (-8950 1125);
DOT 1 (-8950 1675);
DOT 1 (-8950 2050);
DOT 1 (-7925 825);
DOT 1 (-7475 825);
DOT 1 (-7925 1125);
DOT 1 (-7925 1400);
DOT 1 (-7925 1675);
DOT 1 (-7925 2050);
DOT 1 (-7475 1125);
DOT 1 (-7475 1400);
DOT 1 (-7475 1675);
DOT 1 (-7475 2050);
DOT 1 (-6275 825);
DOT 1 (-6275 1400);
DOT 1 (-6275 1125);
DOT 1 (-6275 2050);
DOT 1 (-6275 1675);
DOT 1 (-7925 2325);
DOT 1 (-7925 2525);
DOT 1 (-7475 2525);
DOT 1 (-6275 2325);
DOT 1 (-6275 2525);
DOT 1 (-5800 825);
DOT 1 (-5800 1125);
DOT 1 (-5800 1400);
DOT 1 (-5800 1675);
DOT 1 (-5800 2050);
DOT 1 (-4625 825);
DOT 1 (-4150 825);
DOT 1 (-4625 1125);
DOT 1 (-4625 1400);
DOT 1 (-4150 1125);
DOT 1 (-4150 2050);
DOT 1 (-4150 1675);
DOT 1 (-5800 2325);
DOT 1 (-5800 2525);
DOT 1 (-4625 2325);
DOT 1 (-4150 2325);
DOT 1 (-4150 2525);
DOT 1 (-2175 1125);
DOT 1 (-2175 1400);
DOT 1 (-2175 2050);
DOT 1 (-2175 1675);
DOT 1 (-2175 2325);
DOT 1 (-4275 5275);
DOT 1 (-8950 3600);
DOT 1 (-8950 3725);
DOT 1 (-8950 3975);
DOT 1 (-8950 5175);
DOT 1 (-8950 4800);
DOT 1 (-8950 4925);
DOT 1 (-8950 5450);
DOT 1 (-4275 4375);
FORCENOTE
SPI_CPU0_CLK
(-7400 2175) 0;
DISPLAY LEFT (-7400 2175);
DISPLAY 1.021277 (-7400 2175);
PAINT WHITE (-7400 2175);
FORCENOTE
CPU0 NET NAME
(-7400 2400) 0;
DISPLAY LEFT (-7400 2400);
DISPLAY 1.021277 (-7400 2400);
PAINT WHITE (-7400 2400);
FORCENOTE
UART_CPU0_SCM_UART1_TX
(-7400 1900) 0;
DISPLAY LEFT (-7400 1900);
DISPLAY 1.021277 (-7400 1900);
PAINT WHITE (-7400 1900);
FORCENOTE
CPU0_ROM_TYPE_SELECT
(-7400 1775) 0;
DISPLAY LEFT (-7400 1775);
DISPLAY 1.021277 (-7400 1775);
PAINT WHITE (-7400 1775);
FORCENOTE
CLK_ESPI_CPU0_CLK1
(-7400 1500) 0;
DISPLAY LEFT (-7400 1500);
DISPLAY 1.021277 (-7400 1500);
PAINT WHITE (-7400 1500);
FORCENOTE
ESPI_CLK2||AGPIO74
(-8850 925) 0;
DISPLAY LEFT (-8850 925);
DISPLAY 1.021277 (-8850 925);
PAINT WHITE (-8850 925);
FORCENOTE
ESPI_CLK1
(-8850 1500) 0;
DISPLAY LEFT (-8850 1500);
DISPLAY 1.021277 (-8850 1500);
PAINT WHITE (-8850 1500);
FORCENOTE
50K PD
(-7850 2175) 0;
DISPLAY LEFT (-7850 2175);
DISPLAY 1.021277 (-7850 2175);
PAINT WHITE (-7850 2175);
FORCENOTE
AGPIO109
(-8850 1725) 0;
DISPLAY LEFT (-8850 1725);
DISPLAY 1.021277 (-8850 1725);
PAINT WHITE (-8850 1725);
FORCENOTE
UART1_TXD||AGPIO142
(-8850 1875) 0;
DISPLAY LEFT (-8850 1875);
DISPLAY 1.021277 (-8850 1875);
PAINT WHITE (-8850 1875);
FORCENOTE
CPUX PIN NAME
(-8850 2375) 0;
DISPLAY LEFT (-8850 2375);
DISPLAY 1.021277 (-8850 2375);
PAINT WHITE (-8850 2375);
FORCENOTE
CLKCPU1_RTCCLK
(-5750 1225) 0;
DISPLAY LEFT (-5750 1225);
DISPLAY 1.021277 (-5750 1225);
PAINT WHITE (-5750 1225);
FORCENOTE
CLK_CPU0_RTCCLK
(-7400 1225) 0;
DISPLAY LEFT (-7400 1225);
DISPLAY 1.021277 (-7400 1225);
PAINT WHITE (-7400 1225);
FORCENOTE
0: TOP HALF 64MB ROM
(-4100 1500) 0;
DISPLAY LEFT (-4100 1500);
DISPLAY 1.021277 (-4100 1500);
PAINT WHITE (-4100 1500);
FORCENOTE
1: BOTTOM HALF 64MB ROM
(-4100 1425) 0;
DISPLAY LEFT (-4100 1425);
DISPLAY 1.021277 (-4100 1425);
PAINT WHITE (-4100 1425);
FORCENOTE
0
(-6025 1225) 0;
DISPLAY LEFT (-6025 1225);
DISPLAY 1.021277 (-6025 1225);
PAINT WHITE (-6025 1225);
FORCENOTE
PD_ESPI_CPU0_CLK2
(-7400 925) 0;
DISPLAY LEFT (-7400 925);
DISPLAY 1.021277 (-7400 925);
PAINT WHITE (-7400 925);
FORCENOTE
PD_ESPI_CPU0_CLK2
(-5750 925) 0;
DISPLAY LEFT (-5750 925);
DISPLAY 1.021277 (-5750 925);
PAINT WHITE (-5750 925);
FORCENOTE
0
(-4425 925) 0;
DISPLAY LEFT (-4425 925);
DISPLAY 1.021277 (-4425 925);
PAINT WHITE (-4425 925);
FORCENOTE
RSVD
(-4100 950) 0;
DISPLAY LEFT (-4100 950);
DISPLAY 1.021277 (-4100 950);
PAINT WHITE (-4100 950);
FORCENOTE
1: RTCCLK IS INPUT & USED AS BYPASS CLK
(-4100 1175) 0;
DISPLAY LEFT (-4100 1175);
DISPLAY 1.021277 (-4100 1175);
PAINT WHITE (-4100 1175);
FORCENOTE
0: NORMAL MODE, 32KHZ XTAL AS SOURCE
(-4100 1250) 0;
DISPLAY LEFT (-4100 1250);
DISPLAY 1.021277 (-4100 1250);
PAINT WHITE (-4100 1250);
FORCENOTE
DESCRIPTION
(-3450 2400) 0;
DISPLAY LEFT (-3450 2400);
DISPLAY 1.021277 (-3450 2400);
PAINT WHITE (-3450 2400);
FORCENOTE
CLKGEN SELECTION
(-4100 2225) 0;
DISPLAY LEFT (-4100 2225);
DISPLAY 1.021277 (-4100 2225);
PAINT WHITE (-4100 2225);
FORCENOTE
1
(-4425 2175) 0;
DISPLAY LEFT (-4425 2175);
DISPLAY 1.021277 (-4425 2175);
PAINT WHITE (-4425 2175);
FORCENOTE
(DEFAULT)
(-4600 2350) 0;
DISPLAY LEFT (-4600 2350);
DISPLAY 1.021277 (-4600 2350);
PAINT WHITE (-4600 2350);
FORCENOTE
CPU1
(-4525 2425) 0;
DISPLAY LEFT (-4525 2425);
DISPLAY 1.021277 (-4525 2425);
PAINT WHITE (-4525 2425);
FORCENOTE
SPI_CPU1_CLK
(-5750 2175) 0;
DISPLAY LEFT (-5750 2175);
DISPLAY 1.021277 (-5750 2175);
PAINT WHITE (-5750 2175);
FORCENOTE
00: RSVD
(-4100 1800) 0;
DISPLAY LEFT (-4100 1800);
DISPLAY 1.021277 (-4100 1800);
PAINT WHITE (-4100 1800);
FORCENOTE
1X: ESPI
(-4100 1725) 0;
DISPLAY LEFT (-4100 1725);
DISPLAY 1.021277 (-4100 1725);
PAINT WHITE (-4100 1725);
FORCENOTE
01: SPI ROM(DEFAULT)
(-4100 1875) 0;
DISPLAY LEFT (-4100 1875);
DISPLAY 1.021277 (-4100 1875);
PAINT WHITE (-4100 1875);
FORCENOTE
INTERNAL
(-7875 2450) 0;
DISPLAY LEFT (-7875 2450);
DISPLAY 1.021277 (-7875 2450);
PAINT WHITE (-7875 2450);
FORCENOTE
(DEFAULT)
(-6225 2350) 0;
DISPLAY LEFT (-6225 2350);
DISPLAY 1.021277 (-6225 2350);
PAINT WHITE (-6225 2350);
FORCENOTE
CPU0
(-6150 2425) 0;
DISPLAY LEFT (-6150 2425);
DISPLAY 1.021277 (-6150 2425);
PAINT WHITE (-6150 2425);
FORCENOTE
0
(-6025 925) 0;
DISPLAY LEFT (-6025 925);
DISPLAY 1.021277 (-6025 925);
PAINT WHITE (-6025 925);
FORCENOTE
PD
(-7850 925) 0;
DISPLAY LEFT (-7850 925);
DISPLAY 1.021277 (-7850 925);
PAINT WHITE (-7850 925);
FORCENOTE
0
(-4425 1225) 0;
DISPLAY LEFT (-4425 1225);
DISPLAY 1.021277 (-4425 1225);
PAINT WHITE (-4425 1225);
FORCENOTE
PD
(-7850 1225) 0;
DISPLAY LEFT (-7850 1225);
DISPLAY 1.021277 (-7850 1225);
PAINT WHITE (-7850 1225);
FORCENOTE
RTCCLK
(-8850 1225) 0;
DISPLAY LEFT (-8850 1225);
DISPLAY 1.021277 (-8850 1225);
PAINT WHITE (-8850 1225);
FORCENOTE
50K PU
(-7850 1925) 0;
DISPLAY LEFT (-7850 1925);
DISPLAY 1.021277 (-7850 1925);
PAINT WHITE (-7850 1925);
FORCENOTE
1
(-6025 1500) 0;
DISPLAY LEFT (-6025 1500);
DISPLAY 1.021277 (-6025 1500);
PAINT WHITE (-6025 1500);
FORCENOTE
0
(-6050 1900) 0;
DISPLAY LEFT (-6050 1900);
DISPLAY 1.021277 (-6050 1900);
PAINT WHITE (-6050 1900);
FORCENOTE
ALTERNATE IMAGE
(-4100 1575) 0;
DISPLAY LEFT (-4100 1575);
DISPLAY 1.021277 (-4100 1575);
PAINT WHITE (-4100 1575);
FORCENOTE
ROMTYPE
(-4100 1950) 0;
DISPLAY LEFT (-4100 1950);
DISPLAY 1.021277 (-4100 1950);
PAINT WHITE (-4100 1950);
FORCENOTE
0: EXTERNAL CLKGEN MODE
(-4100 2150) 0;
DISPLAY LEFT (-4100 2150);
DISPLAY 1.021277 (-4100 2150);
PAINT WHITE (-4100 2150);
FORCENOTE
1: INTERNAL CLKGEN MODE
(-4100 2075) 0;
DISPLAY LEFT (-4100 2075);
DISPLAY 1.021277 (-4100 2075);
PAINT WHITE (-4100 2075);
FORCENOTE
1
(-6050 2175) 0;
DISPLAY LEFT (-6050 2175);
DISPLAY 1.021277 (-6050 2175);
PAINT WHITE (-6050 2175);
FORCENOTE
1
(-6050 1775) 0;
DISPLAY LEFT (-6050 1775);
DISPLAY 1.021277 (-6050 1775);
PAINT WHITE (-6050 1775);
FORCENOTE
BYPASS RTC
(-4100 1325) 0;
DISPLAY LEFT (-4100 1325);
DISPLAY 1.021277 (-4100 1325);
PAINT WHITE (-4100 1325);
FORCENOTE
CPU1 STRAP
(-4400 6075) 0;
DISPLAY LEFT (-4400 6075);
DISPLAY 3.297872 (-4400 6075);
PAINT WHITE (-4400 6075);
FORCENOTE
CPU0 STRAP
(-9050 6150) 0;
DISPLAY LEFT (-9050 6150);
DISPLAY 3.297872 (-9050 6150);
PAINT WHITE (-9050 6150);
FORCENOTE
CPU1 NET NAME
(-5750 2375) 0;
DISPLAY LEFT (-5750 2375);
DISPLAY 1.021277 (-5750 2375);
PAINT WHITE (-5750 2375);
FORCENOTE
50K PD
(-7850 1500) 0;
DISPLAY LEFT (-7850 1500);
DISPLAY 1.021277 (-7850 1500);
PAINT WHITE (-7850 1500);
FORCENOTE
PU/PD
(-7875 2375) 0;
DISPLAY LEFT (-7875 2375);
DISPLAY 1.021277 (-7875 2375);
PAINT WHITE (-7875 2375);
FORCENOTE
50K PU
(-7850 1800) 0;
DISPLAY LEFT (-7850 1800);
DISPLAY 1.021277 (-7850 1800);
PAINT WHITE (-7850 1800);
FORCENOTE
ESPI_CLK0
(-8850 2175) 0;
DISPLAY LEFT (-8850 2175);
DISPLAY 1.021277 (-8850 2175);
PAINT WHITE (-8850 2175);
QUIT
